# BASEBOARD_FAB2 (Tioga Pass) — schematic netlist excerpt (pin names and nets, part order shuffled) for the footprints in the layout excerpt that follows; sources: Cadence DE-HDL packaged netlist, KiCad conversion of Wiwynn_Tioga_Pass_MB.brd

R6P20  RES  1.00K 1% CHIP  pkg 0402  page 102 : A = FM_DB1200_SMB_SA1 ; B = GND
C6W3  CAP_A  0.1UF 16V 10% X7R  pkg 0402V  page 247 : A = P3V3_STBY ; B = GND
C2L5  CAP_A  0.01UF 25V 10% X7R  pkg 0402V  page 173 : A = SATA6G_PCH_PCIE_UP_SATA_RXN<7> ; B = SATA6G_P7_RX_C_DN

(kicad_pcb
	(version 20260206)
	(generator "pcbnew")
	(generator_version "10.0")
	(general
		(thickness 1.6)
		(legacy_teardrops no)
	)
	(paper "A4")
	(title_block
		(title "Wiwynn_Tioga_Pass_MB.brd")
		(comment 1 "Tioga Pass / footprints 2482-2484 of 4770")
	)
	(layers
		(0 "F.Cu" signal "TOP")
		(4 "In1.Cu" signal "L2GND")
		(6 "In2.Cu" signal "L3")
		(8 "In3.Cu" signal "L4GND")
		(10 "In4.Cu" signal "L5")
		(12 "In5.Cu" signal "L6GND")
		(14 "In6.Cu" signal "L7VCC")
		(16 "In7.Cu" signal "L8VCC")
		(18 "In8.Cu" signal "L9GND")
		(20 "In9.Cu" signal "L10")
		(22 "In10.Cu" signal "L11GND")
		(24 "In11.Cu" signal "L12")
		(26 "In12.Cu" signal "L13GND")
		(2 "B.Cu" signal "BOTTOM")
		(9 "F.Adhes" user "F.Adhesive")
		(11 "B.Adhes" user "B.Adhesive")
		(13 "F.Paste" user "Package Geometry/Pastemask Top")
		(15 "B.Paste" user "Package Geometry/Pastemask Bottom")
		(5 "F.SilkS" user "Ref Des/Silkscreen Top")
		(7 "B.SilkS" user "Ref Des/Silkscreen Bottom")
		(1 "F.Mask" user "Board Geometry/Soldermask Top")
		(3 "B.Mask" user "Board Geometry/Soldermask Bottom")
		(17 "Dwgs.User" user "User.Drawings")
		(19 "Cmts.User" user "User.Comments")
		(21 "Eco1.User" user "User.Eco1")
		(23 "Eco2.User" user "User.Eco2")
		(25 "Edge.Cuts" user "Board Geometry/Outline")
		(27 "Margin" user)
		(31 "F.CrtYd" user "Package Geometry/Place Bound Top")
		(29 "B.CrtYd" user "Package Geometry/Place Bound Bottom")
		(35 "F.Fab" user "Ref Des/Assembly Top")
		(33 "B.Fab" user "Ref Des/Assembly Bottom")
	)
	(footprint ""
		(layer "B.Cu")
		(at 173.482 -74.8792)
		(property "Reference" "R6P20"
			(at 0 0 0)
			(layer "B.SilkS")
			(hide yes)
			(effects
				(font
					(size 1.27 1.27)
				)
				(justify mirror)
			)
		)
		(property "Value" ""
			(at 0 0 0)
			(layer "B.Fab")
			(effects
				(font
					(size 1.27 1.27)
				)
				(justify mirror)
			)
		)
		(duplicate_pad_numbers_are_jumpers no)
		(fp_poly
			(pts
				(xy 0.2794 -0.1016) (xy -0.2794 -0.1016) (xy -0.2794 0.9906) (xy 0.2794 0.9906)
			)
			(stroke
				(width 0)
				(type default)
			)
			(fill no)
			(layer "B.CrtYd")
		)
		(fp_line
			(start -0.2794 -0.1016)
			(end 0.2794 -0.1016)
			(stroke
				(width 0.1)
				(type default)
			)
			(layer "B.Fab")
		)
		(fp_line
			(start -0.2794 0.9906)
			(end -0.2794 -0.1016)
			(stroke
				(width 0.1)
				(type default)
			)
			(layer "B.Fab")
		)
		(fp_line
			(start 0.2794 -0.1016)
			(end 0.2794 0.9906)
			(stroke
				(width 0.1)
				(type default)
			)
			(layer "B.Fab")
		)
		(fp_line
			(start 0.2794 0.9906)
			(end -0.2794 0.9906)
			(stroke
				(width 0.1)
				(type default)
			)
			(layer "B.Fab")
		)
		(pad "1" smd rect
			(at 0 0 180)
			(size 0.508 0.508)
			(layers "B.Cu" "B.Mask" "B.Paste")
			(net "FM_DB1200_SMB_SA1")
		)
		(pad "2" smd rect
			(at 0 0.889 180)
			(size 0.508 0.508)
			(layers "B.Cu" "B.Mask" "B.Paste")
			(net "GND")
		)
		(zone
			(layer "B.Cu")
			(hatch none 0.5)
			(connect_pads
				(clearance 0)
			)
			(min_thickness 0.25)
			(keepout
				(tracks allowed)
				(vias not_allowed)
				(pads allowed)
				(copperpour not_allowed)
				(footprints allowed)
			)
			(placement
				(enabled no)
				(sheetname "")
			)
			(fill
				(thermal_gap 0.5)
				(thermal_bridge_width 0.5)
				(island_removal_mode 0)
			)
			(polygon
				(pts
					(xy 173.736 -74.6252) (xy 173.228 -74.6252) (xy 173.228 -74.2442) (xy 173.736 -74.2442)
				)
			)
		)
		(zone
			(layer "B.Cu")
			(hatch none 0.5)
			(connect_pads
				(clearance 0)
			)
			(min_thickness 0.25)
			(keepout
				(tracks not_allowed)
				(vias allowed)
				(pads allowed)
				(copperpour not_allowed)
				(footprints allowed)
			)
			(placement
				(enabled no)
				(sheetname "")
			)
			(fill
				(thermal_gap 0.5)
				(thermal_bridge_width 0.5)
				(island_removal_mode 0)
			)
			(polygon
				(pts
					(xy 173.736 -74.2442) (xy 173.228 -74.2442) (xy 173.228 -74.6252) (xy 173.736 -74.6252)
				)
			)
		)
	)
	(footprint ""
		(layer "B.Cu")
		(at 450.5325 -26.543 -90)
		(property "Reference" "C6W3"
			(at 0.8382 -0.67818 270)
			(unlocked yes)
			(layer "B.SilkS")
			(effects
				(font
					(size 0.4064 0.254)
					(thickness 0.1524)
				)
				(justify left mirror)
			)
		)
		(property "Value" ""
			(at 0 0 90)
			(layer "B.Fab")
			(effects
				(font
					(size 1.27 1.27)
				)
				(justify mirror)
			)
		)
		(duplicate_pad_numbers_are_jumpers no)
		(fp_poly
			(pts
				(xy -0.3048 -0.1016) (xy -0.3048 0.9906) (xy 0.3048 0.9906) (xy 0.3048 -0.1016)
			)
			(stroke
				(width 0)
				(type default)
			)
			(fill no)
			(layer "B.CrtYd")
		)
		(fp_line
			(start -0.3048 0.9906)
			(end -0.3048 -0.1016)
			(stroke
				(width 0.1)
				(type default)
			)
			(layer "B.Fab")
		)
		(fp_line
			(start 0.3048 0.9906)
			(end -0.3048 0.9906)
			(stroke
				(width 0.1)
				(type default)
			)
			(layer "B.Fab")
		)
		(fp_line
			(start -0.3048 -0.1016)
			(end 0.3048 -0.1016)
			(stroke
				(width 0.1)
				(type default)
			)
			(layer "B.Fab")
		)
		(fp_line
			(start 0.3048 -0.1016)
			(end 0.3048 0.9906)
			(stroke
				(width 0.1)
				(type default)
			)
			(layer "B.Fab")
		)
		(pad "1" smd rect
			(at 0 0 90)
			(size 0.508 0.508)
			(layers "B.Cu" "B.Mask" "B.Paste")
			(net "P3V3_STBY")
		)
		(pad "2" smd rect
			(at 0 0.889 90)
			(size 0.508 0.508)
			(layers "B.Cu" "B.Mask" "B.Paste")
			(net "GND")
		)
		(zone
			(layer "B.Cu")
			(hatch none 0.5)
			(connect_pads
				(clearance 0)
			)
			(min_thickness 0.25)
			(keepout
				(tracks not_allowed)
				(vias allowed)
				(pads allowed)
				(copperpour not_allowed)
				(footprints allowed)
			)
			(placement
				(enabled no)
				(sheetname "")
			)
			(fill
				(thermal_gap 0.5)
				(thermal_bridge_width 0.5)
				(island_removal_mode 0)
			)
			(polygon
				(pts
					(xy 449.8975 -26.289) (xy 449.8975 -26.797) (xy 450.2785 -26.797) (xy 450.2785 -26.289)
				)
			)
		)
		(zone
			(layer "B.Cu")
			(hatch none 0.5)
			(connect_pads
				(clearance 0)
			)
			(min_thickness 0.25)
			(keepout
				(tracks allowed)
				(vias not_allowed)
				(pads allowed)
				(copperpour not_allowed)
				(footprints allowed)
			)
			(placement
				(enabled no)
				(sheetname "")
			)
			(fill
				(thermal_gap 0.5)
				(thermal_bridge_width 0.5)
				(island_removal_mode 0)
			)
			(polygon
				(pts
					(xy 450.2785 -26.289) (xy 450.2785 -26.797) (xy 449.8975 -26.797) (xy 449.8975 -26.289)
				)
			)
		)
	)
	(footprint ""
		(layer "B.Cu")
		(at 408.1526 -154.4828 90)
		(property "Reference" "C2L5"
			(at 0 0 90)
			(layer "B.SilkS")
			(hide yes)
			(effects
				(font
					(size 1.27 1.27)
				)
				(justify mirror)
			)
		)
		(property "Value" ""
			(at 0 0 90)
			(layer "B.Fab")
			(effects
				(font
					(size 1.27 1.27)
				)
				(justify mirror)
			)
		)
		(duplicate_pad_numbers_are_jumpers no)
		(fp_poly
			(pts
				(xy -0.3048 -0.1016) (xy -0.3048 0.9906) (xy 0.3048 0.9906) (xy 0.3048 -0.1016)
			)
			(stroke
				(width 0)
				(type default)
			)
			(fill no)
			(layer "B.CrtYd")
		)
		(fp_line
			(start 0.3048 -0.1016)
			(end 0.3048 0.9906)
			(stroke
				(width 0.1)
				(type default)
			)
			(layer "B.Fab")
		)
		(fp_line
			(start -0.3048 -0.1016)
			(end 0.3048 -0.1016)
			(stroke
				(width 0.1)
				(type default)
			)
			(layer "B.Fab")
		)
		(fp_line
			(start 0.3048 0.9906)
			(end -0.3048 0.9906)
			(stroke
				(width 0.1)
				(type default)
			)
			(layer "B.Fab")
		)
		(fp_line
			(start -0.3048 0.9906)
			(end -0.3048 -0.1016)
			(stroke
				(width 0.1)
				(type default)
			)
			(layer "B.Fab")
		)
		(pad "1" smd rect
			(at 0 0 270)
			(size 0.508 0.508)
			(layers "B.Cu" "B.Mask" "B.Paste")
			(net "SATA6G_PCH_PCIE_UP_SATA_RXN<7>")
		)
		(pad "2" smd rect
			(at 0 0.889 270)
			(size 0.508 0.508)
			(layers "B.Cu" "B.Mask" "B.Paste")
			(net "SATA6G_P7_RX_C_DN")
		)
		(zone
			(layer "B.Cu")
			(hatch none 0.5)
			(connect_pads
				(clearance 0)
			)
			(min_thickness 0.25)
			(keepout
				(tracks allowed)
				(vias not_allowed)
				(pads allowed)
				(copperpour not_allowed)
				(footprints allowed)
			)
			(placement
				(enabled no)
				(sheetname "")
			)
			(fill
				(thermal_gap 0.5)
				(thermal_bridge_width 0.5)
				(island_removal_mode 0)
			)
			(polygon
				(pts
					(xy 408.4066 -154.7368) (xy 408.4066 -154.2288) (xy 408.7876 -154.2288) (xy 408.7876 -154.7368)
				)
			)
		)
		(zone
			(layer "B.Cu")
			(hatch none 0.5)
			(connect_pads
				(clearance 0)
			)
			(min_thickness 0.25)
			(keepout
				(tracks not_allowed)
				(vias allowed)
				(pads allowed)
				(copperpour not_allowed)
				(footprints allowed)
			)
			(placement
				(enabled no)
				(sheetname "")
			)
			(fill
				(thermal_gap 0.5)
				(thermal_bridge_width 0.5)
				(island_removal_mode 0)
			)
			(polygon
				(pts
					(xy 408.7876 -154.7368) (xy 408.7876 -154.2288) (xy 408.4066 -154.2288) (xy 408.4066 -154.7368)
				)
			)
		)
	)
)
